(kicad_pcb
	(version 20260206)
	(generator "pcbnew")
	(generator_version "10.0")
	(general
		(thickness 1.6)
		(legacy_teardrops no)
	)
	(paper "A4")
	(title_block
		(title "Bryce Canyon_R.DPB_16317-1_OCP.brd")
		(comment 1 "Bryce Canyon / footprints 1997-2004 of 2099")
	)
	(layers
		(0 "F.Cu" signal "TOP")
		(4 "In1.Cu" signal "L2GND")
		(6 "In2.Cu" signal "L3")
		(8 "In3.Cu" signal "L4VCC")
		(10 "In4.Cu" signal "L5VCC")
		(12 "In5.Cu" signal "L6")
		(14 "In6.Cu" signal "L7GND")
		(2 "B.Cu" signal "BOTTOM")
		(9 "F.Adhes" user "F.Adhesive")
		(11 "B.Adhes" user "B.Adhesive")
		(13 "F.Paste" user "Package Geometry/Pastemask Top")
		(15 "B.Paste" user "Package Geometry/Pastemask Bottom")
		(5 "F.SilkS" user "Ref Des/Silkscreen Top")
		(7 "B.SilkS" user "Ref Des/Silkscreen Bottom")
		(1 "F.Mask" user "Board Geometry/Soldermask Top")
		(3 "B.Mask" user "Board Geometry/Soldermask Bottom")
		(17 "Dwgs.User" user "User.Drawings")
		(19 "Cmts.User" user "User.Comments")
		(21 "Eco1.User" user "User.Eco1")
		(23 "Eco2.User" user "User.Eco2")
		(25 "Edge.Cuts" user "Board Geometry/Outline")
		(27 "Margin" user)
		(31 "F.CrtYd" user "Package Geometry/Place Bound Top")
		(29 "B.CrtYd" user "Package Geometry/Place Bound Bottom")
		(35 "F.Fab" user "Ref Des/Assembly Top")
		(33 "B.Fab" user "Ref Des/Assembly Bottom")
	)
	(footprint ""
		(layer "B.Cu")
		(at 445.963802 -223.01835 180)
		(property "Reference" "C655"
			(at 0 0 0)
			(layer "B.SilkS")
			(hide yes)
			(effects
				(font
					(size 1.27 1.27)
				)
				(justify mirror)
			)
		)
		(property "Value" "SC10U16V5KX-7-GP-U"
			(at 0.0762 -6.1214 180)
			(unlocked yes)
			(layer "B.Fab")
			(hide yes)
			(effects
				(font
					(size 1.016 1.016)
					(thickness 0.1524)
				)
				(justify mirror)
			)
		)
		(property "Device Type" "C805H58"
			(at 0.0762 -8.1534 180)
			(unlocked yes)
			(layer "B.Fab")
			(hide yes)
			(effects
				(font
					(size 1.016 1.016)
					(thickness 0.1524)
				)
				(justify mirror)
			)
		)
		(duplicate_pad_numbers_are_jumpers no)
		(fp_line
			(start -0.635 0)
			(end 0.635 0)
			(stroke
				(width 0.508)
				(type default)
			)
			(layer "B.SilkS")
		)
		(fp_rect
			(start 0.9652 1.778)
			(end -0.9652 -1.778)
			(stroke
				(width 0)
				(type default)
			)
			(fill no)
			(layer "B.CrtYd")
		)
		(fp_poly
			(pts
				(xy 0.9652 -1.778) (xy -0.9652 -1.778) (xy -0.9652 1.778) (xy 0.9652 1.778)
			)
			(stroke
				(width 0)
				(type default)
			)
			(fill no)
			(layer "B.Fab")
		)
		(pad "1" smd rect
			(at 0 -0.9652)
			(size 1.397 1.143)
			(layers "B.Cu" "B.Mask" "B.Paste")
			(net "P12V_B_3_VIN_U33")
		)
		(pad "2" smd rect
			(at 0 0.9652)
			(size 1.397 1.143)
			(layers "B.Cu" "B.Mask" "B.Paste")
			(net "GND")
		)
	)
	(footprint ""
		(layer "B.Cu")
		(at 447.995802 -223.01835 180)
		(property "Reference" "C654"
			(at 0 0 0)
			(layer "B.SilkS")
			(hide yes)
			(effects
				(font
					(size 1.27 1.27)
				)
				(justify mirror)
			)
		)
		(property "Value" "SC10U16V5KX-7-GP-U"
			(at 0.0762 -6.1214 180)
			(unlocked yes)
			(layer "B.Fab")
			(hide yes)
			(effects
				(font
					(size 1.016 1.016)
					(thickness 0.1524)
				)
				(justify mirror)
			)
		)
		(property "Device Type" "C805H58"
			(at 0.0762 -8.1534 180)
			(unlocked yes)
			(layer "B.Fab")
			(hide yes)
			(effects
				(font
					(size 1.016 1.016)
					(thickness 0.1524)
				)
				(justify mirror)
			)
		)
		(duplicate_pad_numbers_are_jumpers no)
		(fp_line
			(start -0.635 0)
			(end 0.635 0)
			(stroke
				(width 0.508)
				(type default)
			)
			(layer "B.SilkS")
		)
		(fp_rect
			(start 0.9652 1.778)
			(end -0.9652 -1.778)
			(stroke
				(width 0)
				(type default)
			)
			(fill no)
			(layer "B.CrtYd")
		)
		(fp_poly
			(pts
				(xy 0.9652 -1.778) (xy -0.9652 -1.778) (xy -0.9652 1.778) (xy 0.9652 1.778)
			)
			(stroke
				(width 0)
				(type default)
			)
			(fill no)
			(layer "B.Fab")
		)
		(pad "1" smd rect
			(at 0 -0.9652)
			(size 1.397 1.143)
			(layers "B.Cu" "B.Mask" "B.Paste")
			(net "P12V_B_3_VIN_U33")
		)
		(pad "2" smd rect
			(at 0 0.9652)
			(size 1.397 1.143)
			(layers "B.Cu" "B.Mask" "B.Paste")
			(net "GND")
		)
	)
	(footprint ""
		(layer "B.Cu")
		(at 463.292698 -118.013226 180)
		(property "Reference" "C688"
			(at 0 0 0)
			(layer "B.SilkS")
			(hide yes)
			(effects
				(font
					(size 1.27 1.27)
				)
				(justify mirror)
			)
		)
		(property "Value" "SC10U16V5KX-7-GP-U"
			(at 0.0762 -6.1214 180)
			(unlocked yes)
			(layer "B.Fab")
			(hide yes)
			(effects
				(font
					(size 1.016 1.016)
					(thickness 0.1524)
				)
				(justify mirror)
			)
		)
		(property "Device Type" "C805H58"
			(at 0.0762 -8.1534 180)
			(unlocked yes)
			(layer "B.Fab")
			(hide yes)
			(effects
				(font
					(size 1.016 1.016)
					(thickness 0.1524)
				)
				(justify mirror)
			)
		)
		(duplicate_pad_numbers_are_jumpers no)
		(fp_line
			(start -0.635 0)
			(end 0.635 0)
			(stroke
				(width 0.508)
				(type default)
			)
			(layer "B.SilkS")
		)
		(fp_rect
			(start 0.9652 1.778)
			(end -0.9652 -1.778)
			(stroke
				(width 0)
				(type default)
			)
			(fill no)
			(layer "B.CrtYd")
		)
		(fp_poly
			(pts
				(xy 0.9652 -1.778) (xy -0.9652 -1.778) (xy -0.9652 1.778) (xy 0.9652 1.778)
			)
			(stroke
				(width 0)
				(type default)
			)
			(fill no)
			(layer "B.Fab")
		)
		(pad "1" smd rect
			(at 0 -0.9652)
			(size 1.397 1.143)
			(layers "B.Cu" "B.Mask" "B.Paste")
			(net "P5V_B_4")
		)
		(pad "2" smd rect
			(at 0 0.9652)
			(size 1.397 1.143)
			(layers "B.Cu" "B.Mask" "B.Paste")
			(net "GND")
		)
	)
	(footprint ""
		(layer "B.Cu")
		(at 447.632328 -118.784624 180)
		(property "Reference" "R1160"
			(at 0 0 0)
			(layer "B.SilkS")
			(hide yes)
			(effects
				(font
					(size 1.27 1.27)
				)
				(justify mirror)
			)
		)
		(property "Value" "2K7R2F-GP"
			(at -0.064008 -3.993896 180)
			(unlocked yes)
			(layer "B.Fab")
			(hide yes)
			(effects
				(font
					(size 1.016 1.016)
					(thickness 0.1524)
				)
				(justify mirror)
			)
		)
		(property "Device Type" "R402H16"
			(at -0.064008 -5.517896 180)
			(unlocked yes)
			(layer "B.Fab")
			(hide yes)
			(effects
				(font
					(size 1.016 1.016)
					(thickness 0.1524)
				)
				(justify mirror)
			)
		)
		(duplicate_pad_numbers_are_jumpers no)
		(fp_line
			(start 0.508 -0.9398)
			(end 0.508 0.9398)
			(stroke
				(width 0.1524)
				(type default)
			)
			(layer "B.SilkS")
		)
		(fp_line
			(start -0.508 -0.9398)
			(end 0.508 -0.9398)
			(stroke
				(width 0.1524)
				(type default)
			)
			(layer "B.SilkS")
		)
		(fp_rect
			(start 0.508 0.9398)
			(end -0.508 -0.9398)
			(stroke
				(width 0)
				(type default)
			)
			(fill no)
			(layer "B.CrtYd")
		)
		(fp_rect
			(start 0.508 0.9398)
			(end -0.508 -0.9398)
			(stroke
				(width 0)
				(type default)
			)
			(fill no)
			(layer "B.Fab")
		)
		(pad "1" smd custom
			(at 0 -0.4445)
			(size 0.1397 0.1397)
			(layers "B.Cu" "B.Mask" "B.Paste")
			(net "P5V_B_4_LL")
			(options
				(clearance outline)
				(anchor circle)
			)
			(primitives
				(gr_poly
					(pts
						(arc
							(start -0.1778 0.2794)
							(mid -0.249642 0.249642)
							(end -0.2794 0.1778)
						)
						(arc
							(start -0.2794 -0.1778)
							(mid -0.249642 -0.249642)
							(end -0.1778 -0.2794)
						)
						(arc
							(start 0.1778 -0.2794)
							(mid 0.249642 -0.249642)
							(end 0.2794 -0.1778)
						)
						(arc
							(start 0.2794 0.1778)
							(mid 0.249642 0.249642)
							(end 0.1778 0.2794)
						)
					)
					(width 0)
					(fill yes)
				)
			)
		)
		(pad "2" smd custom
			(at 0 0.4445)
			(size 0.1397 0.1397)
			(layers "B.Cu" "B.Mask" "B.Paste")
			(net "P5V_B_4_LL_R")
			(options
				(clearance outline)
				(anchor circle)
			)
			(primitives
				(gr_poly
					(pts
						(arc
							(start -0.1778 0.2794)
							(mid -0.249642 0.249642)
							(end -0.2794 0.1778)
						)
						(arc
							(start -0.2794 -0.1778)
							(mid -0.249642 -0.249642)
							(end -0.1778 -0.2794)
						)
						(arc
							(start 0.1778 -0.2794)
							(mid 0.249642 -0.249642)
							(end 0.2794 -0.1778)
						)
						(arc
							(start 0.2794 0.1778)
							(mid 0.249642 0.249642)
							(end 0.1778 0.2794)
						)
					)
					(width 0)
					(fill yes)
				)
			)
		)
	)
	(footprint ""
		(layer "B.Cu")
		(at 40.66286 -112.087406 180)
		(property "Reference" "C638"
			(at 0 0 0)
			(layer "B.SilkS")
			(hide yes)
			(effects
				(font
					(size 1.27 1.27)
				)
				(justify mirror)
			)
		)
		(property "Value" "SCD1U16V2KX-3GP"
			(at -1.1811 -2.7051 180)
			(unlocked yes)
			(layer "B.Fab")
			(hide yes)
			(effects
				(font
					(size 1.016 1.016)
					(thickness 0.1524)
				)
				(justify mirror)
			)
		)
		(property "Device Type" "C402H22"
			(at -1.1811 -4.2291 180)
			(unlocked yes)
			(layer "B.Fab")
			(hide yes)
			(effects
				(font
					(size 1.016 1.016)
					(thickness 0.1524)
				)
				(justify mirror)
			)
		)
		(duplicate_pad_numbers_are_jumpers no)
		(fp_rect
			(start 0.4318 0.9525)
			(end -0.4318 -0.9525)
			(stroke
				(width 0)
				(type default)
			)
			(fill no)
			(layer "B.CrtYd")
		)
		(fp_rect
			(start 0.4318 0.9525)
			(end -0.4318 -0.9525)
			(stroke
				(width 0)
				(type default)
			)
			(fill no)
			(layer "B.Fab")
		)
		(pad "1" smd custom
			(at 0 -0.4445)
			(size 0.1524 0.1524)
			(layers "B.Cu" "B.Mask" "B.Paste")
			(net "P12V_B_2_VIN_U32")
			(options
				(clearance outline)
				(anchor circle)
			)
			(primitives
				(gr_poly
					(pts
						(arc
							(start 0.3048 0.2032)
							(mid 0.275042 0.275042)
							(end 0.2032 0.3048)
						)
						(arc
							(start -0.2032 0.3048)
							(mid -0.275042 0.275042)
							(end -0.3048 0.2032)
						)
						(arc
							(start -0.3048 -0.2032)
							(mid -0.275042 -0.275042)
							(end -0.2032 -0.3048)
						)
						(arc
							(start 0.2032 -0.3048)
							(mid 0.275042 -0.275042)
							(end 0.3048 -0.2032)
						)
					)
					(width 0)
					(fill yes)
				)
			)
		)
		(pad "2" smd custom
			(at 0 0.4445)
			(size 0.1524 0.1524)
			(layers "B.Cu" "B.Mask" "B.Paste")
			(net "GND")
			(options
				(clearance outline)
				(anchor circle)
			)
			(primitives
				(gr_poly
					(pts
						(arc
							(start 0.3048 0.2032)
							(mid 0.275042 0.275042)
							(end 0.2032 0.3048)
						)
						(arc
							(start -0.2032 0.3048)
							(mid -0.275042 0.275042)
							(end -0.3048 0.2032)
						)
						(arc
							(start -0.3048 -0.2032)
							(mid -0.275042 -0.275042)
							(end -0.2032 -0.3048)
						)
						(arc
							(start 0.2032 -0.3048)
							(mid 0.275042 -0.275042)
							(end 0.3048 -0.2032)
						)
					)
					(width 0)
					(fill yes)
				)
			)
		)
	)
	(footprint ""
		(layer "B.Cu")
		(at 476.6564 -230.09479 180)
		(property "Reference" "TC9"
			(at 0 0 0)
			(layer "B.SilkS")
			(hide yes)
			(effects
				(font
					(size 1.27 1.27)
				)
				(justify mirror)
			)
		)
		(property "Value" "ST220U10VDM-LGP"
			(at 0 -9.6012 180)
			(unlocked yes)
			(layer "B.Fab")
			(hide yes)
			(effects
				(font
					(size 1.016 1.016)
					(thickness 0.1524)
				)
				(justify mirror)
			)
		)
		(property "Device Type" "CT7343H119"
			(at 0 -11.1252 180)
			(unlocked yes)
			(layer "B.Fab")
			(hide yes)
			(effects
				(font
					(size 1.016 1.016)
					(thickness 0.1524)
				)
				(justify mirror)
			)
		)
		(duplicate_pad_numbers_are_jumpers no)
		(fp_line
			(start 2.286 4.8768)
			(end 2.286 2.032)
			(stroke
				(width 0.1524)
				(type default)
			)
			(layer "B.SilkS")
		)
		(fp_line
			(start 2.286 -4.8768)
			(end 2.286 -2.032)
			(stroke
				(width 0.1524)
				(type default)
			)
			(layer "B.SilkS")
		)
		(fp_line
			(start -2.1082 -4.699)
			(end 2.1082 -4.699)
			(stroke
				(width 0.508)
				(type default)
			)
			(layer "B.SilkS")
		)
		(fp_line
			(start -2.286 4.8768)
			(end 2.286 4.8768)
			(stroke
				(width 0.1524)
				(type default)
			)
			(layer "B.SilkS")
		)
		(fp_line
			(start -2.286 2.032)
			(end -2.286 4.8768)
			(stroke
				(width 0.1524)
				(type default)
			)
			(layer "B.SilkS")
		)
		(fp_line
			(start -2.286 -2.032)
			(end -2.286 -4.8768)
			(stroke
				(width 0.1524)
				(type default)
			)
			(layer "B.SilkS")
		)
		(fp_line
			(start -2.286 -4.8768)
			(end 2.286 -4.8768)
			(stroke
				(width 0.1524)
				(type default)
			)
			(layer "B.SilkS")
		)
		(fp_rect
			(start 2.1463 3.6449)
			(end -2.1463 -3.6449)
			(stroke
				(width 0)
				(type default)
			)
			(fill no)
			(layer "B.CrtYd")
		)
		(fp_poly
			(pts
				(xy 2.54 4.953) (xy 2.54 4.2926) (xy 3.81 4.2926) (xy 3.81 -4.2926) (xy 2.54 -4.2926) (xy 2.54 -4.953)
				(xy -2.54 -4.953) (xy -2.54 -4.2926) (xy -3.81 -4.2926) (xy -3.81 -1.6256) (xy -2.1463 -1.6256)
				(xy -2.1463 -3.6449) (xy 2.1463 -3.6449) (xy 2.1463 3.6449) (xy -2.1463 3.6449) (xy -2.1463 -1.6129)
				(xy -3.81 -1.6129) (xy -3.81 4.2926) (xy -2.54 4.2926) (xy -2.54 4.953)
			)
			(stroke
				(width 0)
				(type default)
			)
			(fill no)
			(layer "B.CrtYd")
		)
		(fp_rect
			(start 3.81 4.2926)
			(end 2.54 -4.2926)
			(stroke
				(width 0)
				(type default)
			)
			(fill no)
			(layer "B.Fab")
		)
		(fp_rect
			(start 2.54 4.953)
			(end -2.54 -4.953)
			(stroke
				(width 0)
				(type default)
			)
			(fill no)
			(layer "B.Fab")
		)
		(fp_rect
			(start -2.54 4.2926)
			(end -3.81 -4.2926)
			(stroke
				(width 0)
				(type default)
			)
			(fill no)
			(layer "B.Fab")
		)
		(pad "1" smd rect
			(at 0 -3.1496)
			(size 2.413 2.286)
			(layers "B.Cu" "B.Mask" "B.Paste")
			(net "P5V_B_3")
		)
		(pad "2" smd rect
			(at 0 3.1496)
			(size 2.413 2.286)
			(layers "B.Cu" "B.Mask" "B.Paste")
			(net "GND")
		)
		(zone
			(layer "B.Cu")
			(hatch none 0.5)
			(connect_pads
				(clearance 0)
			)
			(min_thickness 0.25)
			(keepout
				(tracks allowed)
				(vias not_allowed)
				(pads allowed)
				(copperpour not_allowed)
				(footprints allowed)
			)
			(placement
				(enabled no)
				(sheetname "")
			)
			(fill
				(thermal_gap 0.5)
				(thermal_bridge_width 0.5)
				(island_removal_mode 0)
			)
			(polygon
				(pts
					(xy 475.1451 -234.69219) (xy 478.1677 -234.69219) (xy 478.1677 -231.79659) (xy 478.1677 -231.46639)
					(xy 475.1451 -231.46639) (xy 475.1451 -231.79659)
				)
			)
		)
		(zone
			(layer "B.Cu")
			(hatch none 0.5)
			(connect_pads
				(clearance 0)
			)
			(min_thickness 0.25)
			(keepout
				(tracks allowed)
				(vias not_allowed)
				(pads allowed)
				(copperpour not_allowed)
				(footprints allowed)
			)
			(placement
				(enabled no)
				(sheetname "")
			)
			(fill
				(thermal_gap 0.5)
				(thermal_bridge_width 0.5)
				(island_removal_mode 0)
			)
			(polygon
				(pts
					(xy 478.1677 -228.40569) (xy 478.1677 -225.49739) (xy 475.1451 -225.49739) (xy 475.1451 -228.39299)
					(xy 475.1451 -228.72319) (xy 478.1677 -228.72319)
				)
			)
		)
	)
	(footprint ""
		(layer "B.Cu")
		(at 465.225892 -118.015258 180)
		(property "Reference" "C687"
			(at 0 0 0)
			(layer "B.SilkS")
			(hide yes)
			(effects
				(font
					(size 1.27 1.27)
				)
				(justify mirror)
			)
		)
		(property "Value" "SC10U16V5KX-7-GP-U"
			(at 0.0762 -6.1214 180)
			(unlocked yes)
			(layer "B.Fab")
			(hide yes)
			(effects
				(font
					(size 1.016 1.016)
					(thickness 0.1524)
				)
				(justify mirror)
			)
		)
		(property "Device Type" "C805H58"
			(at 0.0762 -8.1534 180)
			(unlocked yes)
			(layer "B.Fab")
			(hide yes)
			(effects
				(font
					(size 1.016 1.016)
					(thickness 0.1524)
				)
				(justify mirror)
			)
		)
		(duplicate_pad_numbers_are_jumpers no)
		(fp_line
			(start -0.635 0)
			(end 0.635 0)
			(stroke
				(width 0.508)
				(type default)
			)
			(layer "B.SilkS")
		)
		(fp_rect
			(start 0.9652 1.778)
			(end -0.9652 -1.778)
			(stroke
				(width 0)
				(type default)
			)
			(fill no)
			(layer "B.CrtYd")
		)
		(fp_poly
			(pts
				(xy 0.9652 -1.778) (xy -0.9652 -1.778) (xy -0.9652 1.778) (xy 0.9652 1.778)
			)
			(stroke
				(width 0)
				(type default)
			)
			(fill no)
			(layer "B.Fab")
		)
		(pad "1" smd rect
			(at 0 -0.9652)
			(size 1.397 1.143)
			(layers "B.Cu" "B.Mask" "B.Paste")
			(net "P5V_B_4")
		)
		(pad "2" smd rect
			(at 0 0.9652)
			(size 1.397 1.143)
			(layers "B.Cu" "B.Mask" "B.Paste")
			(net "GND")
		)
	)
	(footprint ""
		(layer "B.Cu")
		(at 127.824992 -181.799992)
		(property "Reference" "SCW1"
			(at 0 0 0)
			(layer "B.SilkS")
			(hide yes)
			(effects
				(font
					(size 1.27 1.27)
				)
				(justify mirror)
			)
		)
		(property "Value" ""
			(at 0 0 0)
			(layer "B.Fab")
			(effects
				(font
					(size 1.27 1.27)
				)
				(justify mirror)
			)
		)
		(duplicate_pad_numbers_are_jumpers no)
		(fp_poly
			(pts
				(arc
					(start 5.4356 0)
					(mid -5.4356 0)
					(end 5.4356 0)
				)
			)
			(stroke
				(width 0)
				(type default)
			)
			(fill no)
			(layer "B.CrtYd")
		)
		(fp_poly
			(pts
				(arc
					(start 5.4356 0)
					(mid -5.4356 0)
					(end 5.4356 0)
				)
			)
			(stroke
				(width 0)
				(type default)
			)
			(fill no)
			(layer "F.CrtYd")
		)
		(fp_poly
			(pts
				(arc
					(start 5.4356 0)
					(mid -5.4356 0)
					(end 5.4356 0)
				)
			)
			(stroke
				(width 0)
				(type default)
			)
			(fill no)
			(layer "B.Fab")
		)
		(fp_poly
			(pts
				(arc
					(start 5.4356 0)
					(mid -5.4356 0)
					(end 5.4356 0)
				)
			)
			(stroke
				(width 0)
				(type default)
			)
			(fill no)
			(layer "F.Fab")
		)
		(pad "" np_thru_hole circle
			(at 0 0 180)
			(size 0.254 0.254)
			(drill 10.2616)
			(layers "*.Cu" "*.Mask")
			(clearance 5.3594)
			(thermal_gap 5.3594)
		)
		(zone
			(layers "F.Cu" "B.Cu" "In1.Cu" "In2.Cu" "In3.Cu" "In4.Cu" "In5.Cu" "In6.Cu")
			(hatch none 0.5)
			(connect_pads
				(clearance 0)
			)
			(min_thickness 0.25)
			(keepout
				(tracks not_allowed)
				(vias allowed)
				(pads allowed)
				(copperpour not_allowed)
				(footprints allowed)
			)
			(placement
				(enabled no)
				(sheetname "")
			)
			(fill
				(thermal_gap 0.5)
				(thermal_bridge_width 0.5)
				(island_removal_mode 0)
			)
			(polygon
				(pts
					(arc
						(start 133.260592 -181.799992)
						(mid 122.389392 -181.799992)
						(end 133.260592 -181.799992)
					)
				)
			)
		)
	)
)
